FILE_TYPE = CONNECTIVITY;
{Allegro Design Entry HDL 17.2-2016 S081 (4005846) 1/11/2022}
"PAGE_NUMBER" = 221;
0"NC";
1"P3V3_AUX\g";
2"P3V3_AUX\g";
3"P3V3_AUX\g";
4"P3V3_AUX\g";
5"GND\g";
6"GND\g";
7"GND\g";
8"GND\g";
9"GND\g";
10"SMB_VR_SENSOR_3V3AUX_SDA"CDS_PHYS_NET_NAME"SMB_PCIE0_3V3AUX_SDA";
11"SMB_VR_SENSOR_3V3AUX_SCL"CDS_PHYS_NET_NAME"SMB_PCIE0_3V3AUX_SCL";
12"SMB_LM75_3_3V3AUX_SDA"CDS_PHYS_NET_NAME"SMB_2_PLD_3V3AUX_SDA";
13"SMB_LM75_3_3V3AUX_SCL"CDS_PHYS_NET_NAME"SMB_2_PLD_3V3AUX_SCL";
14"RST_SMB_SWITCH_N"CDS_PHYS_NET_NAME"RST_SMB_SWITCH_N";
15"SMB_VR_3V3AUX_SCL_R6"CDS_PHYS_NET_NAME"SMB_VR_3V3AUX_SCL_R6";
16"SMB_LM75_0_3V3AUX_SDA_R"CDS_PHYS_NET_NAME"SMB_LM75_0_3V3AUX_SDA_R";
17"PU_RST_SMB_PCIE2_N"CDS_PHYS_NET_NAME"PU_RST_SMB_PCIE2_N";
18"SMB_VR_3V3AUX_SDA"CDS_PHYS_NET_NAME"SMB_VR_3V3AUX_SDA";
19"SMB_VR_3V3AUX_SCL"CDS_PHYS_NET_NAME"SMB_VR_3V3AUX_SCL";
20"SMB_LM75_2_3V3AUX_SCL_R"CDS_PHYS_NET_NAME"SMB_LM75_2_3V3AUX_SCL_R";
21"SMB_LM75_2_3V3AUX_SDA_R"CDS_PHYS_NET_NAME"SMB_LM75_2_3V3AUX_SDA_R";
22"SMB_LM75_1_3V3AUX_SCL_R"CDS_PHYS_NET_NAME"SMB_LM75_1_3V3AUX_SCL_R";
23"SMB_LM75_1_3V3AUX_SDA_R"CDS_PHYS_NET_NAME"SMB_LM75_1_3V3AUX_SDA_R";
24"SMB_LM75_0_3V3AUX_SCL_R"CDS_PHYS_NET_NAME"SMB_LM75_0_3V3AUX_SCL_R";
25"SMB_VR_3V3AUX_SDA_R6"CDS_PHYS_NET_NAME"SMB_VR_3V3AUX_SDA_R6";
26"PCA9548_PCIE0_ADDR0";
27"SMB_LM75_3_3V3AUX_SCL_R"CDS_PHYS_NET_NAME"SMB_LM75_3_3V3AUX_SCL_R";
28"SMB_LM75_3_3V3AUX_SCL"CDS_PHYS_NET_NAME"SMB_LM75_3_3V3AUX_SCL";
29"SMB_LM75_3_3V3AUX_SDA"CDS_PHYS_NET_NAME"SMB_LM75_3_3V3AUX_SDA";
30"SMB_VR_SENSOR_3V3AUX_SDA"CDS_PHYS_NET_NAME"SMB_VR_SENSOR_3V3AUX_SDA";
31"SMB_VR_SENSOR_3V3AUX_SCL"CDS_PHYS_NET_NAME"SMB_VR_SENSOR_3V3AUX_SCL";
32"SMB_VR_SENSOR_3V3AUX_SDA_R"CDS_PHYS_NET_NAME"SMB_VR_SENSOR_3V3AUX_SDA_R";
33"SMB_VR_SENSOR_3V3AUX_SCL_R"CDS_PHYS_NET_NAME"SMB_VR_SENSOR_3V3AUX_SCL_R";
34"PCA9548_PCIE0_ADDR2"CDS_PHYS_NET_NAME"PCA9548_PCIE0_ADDR2";
35"SMB_LM75_2_3V3AUX_SCL"CDS_PHYS_NET_NAME"SMB_LM75_2_3V3AUX_SCL";
36"SMB_LM75_2_3V3AUX_SDA"CDS_PHYS_NET_NAME"SMB_LM75_2_3V3AUX_SDA";
37"SMB_LM75_1_3V3AUX_SCL"CDS_PHYS_NET_NAME"SMB_LM75_1_3V3AUX_SCL";
38"SMB_LM75_1_3V3AUX_SDA"CDS_PHYS_NET_NAME"SMB_LM75_1_3V3AUX_SDA";
39"SMB_LM75_0_3V3AUX_SCL"CDS_PHYS_NET_NAME"SMB_LM75_0_3V3AUX_SCL";
40"SMB_LM75_0_3V3AUX_SDA"CDS_PHYS_NET_NAME"SMB_LM75_0_3V3AUX_SDA";
41"SMB_LM75_3_3V3AUX_SDA_R"CDS_PHYS_NET_NAME"SMB_LM75_3_3V3AUX_SDA_R";
42"PCA9548_PCIE0_ADDR1";
43"SMB_LM75_1_3V3AUX_SDA"CDS_PHYS_NET_NAME"SMB_IOEXP_3V3AUX_SDA";
44"SMB_LM75_2_3V3AUX_SCL"CDS_PHYS_NET_NAME"SMB_SENSOR_M2_P1_3V3AUX_SCL";
45"SMB_LM75_2_3V3AUX_SDA"CDS_PHYS_NET_NAME"SMB_SENSOR_M2_P1_3V3AUX_SDA";
46"SMB_LM75_1_3V3AUX_SCL"CDS_PHYS_NET_NAME"SMB_IOEXP_3V3AUX_SCL";
47"SMB_VR_3V3AUX_SCL"CDS_PHYS_NET_NAME"SMB_PCIE0_3V3AUX_SCL";
48"SMB_LM75_0_3V3AUX_SDA"CDS_PHYS_NET_NAME"SMB_INA230_3V3AUX_SDA";
49"SMB_VR_3V3AUX_SDA"CDS_PHYS_NET_NAME"SMB_PCIE0_3V3AUX_SDA";
50"SMB_LM75_0_3V3AUX_SCL"CDS_PHYS_NET_NAME"SMB_INA230_3V3AUX_SCL";
51"PCA9548_PCIE0_ADDR0";
52"PCA9548_PCIE0_ADDR1";
53"PCA9548_PCIE0_ADDR2";
%"UNIVERSAL_GND"
"1","(-3150,-150)","0","logical_power","I1";
;
CDS_LIB"logical_power"
ROOM"IO_SLOT"
HDL_POWER"GND";
"A"9;
%"Q_RES"
"2","(-2600,725)","0","pure_quanta","I10";
;
PART_NUMBER"CS31002FB08"
PACK_TYPE"0402LF"
MATERIAL"EMPTY"
TOLERANCE"1%"
VALUE"10K"
WATTAGE"1/16W"
$LOCATION"R3708"
CDS_LIB"pure_quanta"
CDS_LOCATION"R3708"
$SEC"1"
CDS_SEC"1";
"A"
$PN"1"4;
"B"
$PN"2"51;
%"Q_RES"
"1","(1975,-425)","0","pure_quanta","I102";
;
PART_NUMBER"CS22202JB07"
WATTAGE"1/16W"
PACK_TYPE"0402LF"
MATERIAL"EMPTY"
VALUE"2.2K"
TOLERANCE"5%"
$LOCATION"R4269"
CDS_LIB"pure_quanta"
CDS_LOCATION"R4269"
$SEC"1"
CDS_SEC"1";
"B"
$PN"2"11;
"A"
$PN"1"3;
%"TCA9548APWR"
"1","(250,2525)","0","pure_quanta","I103";
;
PART_NUMBER"AL009548K02"
PART_TYPE"SMLF"
MATERIAL"IC"
VALUE"TCA9548APWR"
LOCATION"U39"
CDS_LIB"pure_quanta"
CDS_LMAN_SYM_OUTLINE"-200,475,200,-475"
NEEDS_NO_SIZE"TRUE"
SEC_TYPE""
SEC"1";
"SD4"
$PN"13"41;
"SC4"
$PN"14"27;
"SD5"
$PN"15"0;
"SC5"
$PN"16"0;
"SD6"
$PN"17"0;
"SC6"
$PN"18"0;
"SD7"
$PN"19"0;
"SC7"
$PN"20"0;
"A2"
$PN"21"34;
"SCL"
$PN"22"33;
"SDA"
$PN"23"32;
"VCC"
$PN"24"2;
"GND"
$PN"12"6;
"SC3"
$PN"11"20;
"SD3"
$PN"10"21;
"SC2"
$PN"9"22;
"SD2"
$PN"8"23;
"SC1"
$PN"7"24;
"SD1"
$PN"6"16;
"SC0"
$PN"5"15;
"SD0"
$PN"4"25;
"RESET# \B"
$PN"3"17;
"A1"
$PN"2"42;
"A0"
$PN"1"26;
%"UNIVERSAL_POWER"
"1","(-625,3600)","0","logical_power","I104";
;
HDL_POWER"P3V3_AUX"
CDS_LIB"logical_power";
"A"2;
%"UNIVERSAL_GND"
"1","(-625,3050)","0","logical_power","I105";
;
CDS_LIB"logical_power"
HDL_POWER"GND";
"A"5;
%"Q_CAP"
"1","(-625,3275)","0","pure_quanta","I106";
;
PART_NUMBER"CH4104K1B00"
VOLTAGE"25V"
VALUE"0.1UF"
TOLERANCE"10%"
MATERIAL"X7R"
PACK_TYPE"0402"
$LOCATION"C2056"
CDS_LIB"pure_quanta"
CDS_LOCATION"C2056"
$SEC"1"
CDS_SEC"1";
"B"
$PN"2"5;
"A"
$PN"1"2;
%"Q_RES"
"1","(1700,2800)","2","pure_quanta","I115";
;
PART_NUMBER"CS03322FB03"
VALUE"33.2"
TOLERANCE"1%"
MATERIAL"CHIP"
$LOCATION"R3712"
WATTAGE"1/16W"
CDS_LIB"pure_quanta"
PACK_TYPE"0402LF"
CDS_LOCATION"R3712"
$SEC"1"
CDS_SEC"1";
"B"
$PN"2"32;
"A"
$PN"1"30;
%"Q_RES"
"1","(1700,2750)","2","pure_quanta","I116";
;
PART_NUMBER"CS03322FB03"
PACK_TYPE"0402LF"
VALUE"33.2"
TOLERANCE"1%"
MATERIAL"CHIP"
WATTAGE"1/16W"
$LOCATION"R3711"
CDS_LIB"pure_quanta"
CDS_LOCATION"R3711"
$SEC"1"
CDS_SEC"1";
"B"
$PN"2"33;
"A"
$PN"1"31;
%"Q_RES"
"1","(1575,2550)","0","pure_quanta","I119";
;
PART_NUMBER"CS00002JB13"
MATERIAL"CHIP"
TOLERANCE"5%"
VALUE"0"
$LOCATION"R3722"
CDS_LIB"pure_quanta"
PACK_TYPE"0402LF"
WATTAGE"1/16W"
CDS_LOCATION"R3722"
$SEC"1"
CDS_SEC"1";
"B"
$PN"2"29;
"A"
$PN"1"41;
%"Q_RES"
"1","(1575,2500)","0","pure_quanta","I120";
;
PART_NUMBER"CS00002JB13"
MATERIAL"CHIP"
TOLERANCE"5%"
VALUE"0"
$LOCATION"R3721"
CDS_LIB"pure_quanta"
WATTAGE"1/16W"
PACK_TYPE"0402LF"
CDS_LOCATION"R3721"
$SEC"1"
CDS_SEC"1";
"B"
$PN"2"28;
"A"
$PN"1"27;
%"Q_RES"
"1","(-1075,2500)","2","pure_quanta","I137";
;
PART_NUMBER"CS00002JB13"
MATERIAL"CHIP"
TOLERANCE"5%"
VALUE"0"
$LOCATION"R3713"
PACK_TYPE"0402LF"
CDS_LIB"pure_quanta"
WATTAGE"1/16W"
CDS_LOCATION"R3713"
$SEC"1"
CDS_SEC"1";
"B"
$PN"2"19;
"A"
$PN"1"15;
%"Q_RES"
"1","(-1075,2550)","2","pure_quanta","I138";
;
PART_NUMBER"CS00002JB13"
MATERIAL"CHIP"
WATTAGE"1/16W"
PACK_TYPE"0402LF"
VALUE"0"
TOLERANCE"5%"
$LOCATION"R3714"
CDS_LIB"pure_quanta"
CDS_LOCATION"R3714"
$SEC"1"
CDS_SEC"1";
"B"
$PN"2"18;
"A"
$PN"1"25;
%"Q_RES"
"1","(-1075,2400)","2","pure_quanta","I139";
;
PART_NUMBER"CS00002JB13"
TOLERANCE"5%"
MATERIAL"CHIP"
VALUE"0"
$LOCATION"R3715"
PACK_TYPE"0402LF"
WATTAGE"1/16W"
CDS_LIB"pure_quanta"
CDS_LOCATION"R3715"
$SEC"1"
CDS_SEC"1";
"B"
$PN"2"39;
"A"
$PN"1"24;
%"Q_RES"
"1","(-1075,2450)","2","pure_quanta","I140";
;
PART_NUMBER"CS00002JB13"
TOLERANCE"5%"
MATERIAL"CHIP"
VALUE"0"
$LOCATION"R3716"
CDS_LIB"pure_quanta"
PACK_TYPE"0402LF"
WATTAGE"1/16W"
CDS_LOCATION"R3716"
$SEC"1"
CDS_SEC"1";
"B"
$PN"2"40;
"A"
$PN"1"16;
%"Q_RES"
"1","(-1075,2300)","2","pure_quanta","I141";
;
PART_NUMBER"CS00002JB13"
TOLERANCE"5%"
MATERIAL"CHIP"
VALUE"0"
$LOCATION"R3717"
PACK_TYPE"0402LF"
WATTAGE"1/16W"
CDS_LIB"pure_quanta"
CDS_LOCATION"R3717"
$SEC"1"
CDS_SEC"1";
"B"
$PN"2"37;
"A"
$PN"1"22;
%"Q_RES"
"1","(-1075,2350)","2","pure_quanta","I142";
;
PART_NUMBER"CS00002JB13"
MATERIAL"CHIP"
VALUE"0"
TOLERANCE"5%"
$LOCATION"R3718"
CDS_LIB"pure_quanta"
PACK_TYPE"0402LF"
WATTAGE"1/16W"
CDS_LOCATION"R3718"
$SEC"1"
CDS_SEC"1";
"B"
$PN"2"38;
"A"
$PN"1"23;
%"Q_RES"
"1","(-1075,2200)","2","pure_quanta","I143";
;
PART_NUMBER"CS00002JB13"
MATERIAL"CHIP"
VALUE"0"
TOLERANCE"5%"
$LOCATION"R3719"
CDS_LIB"pure_quanta"
WATTAGE"1/16W"
PACK_TYPE"0402LF"
CDS_LOCATION"R3719"
$SEC"1"
CDS_SEC"1";
"B"
$PN"2"35;
"A"
$PN"1"20;
%"Q_RES"
"1","(-1075,2250)","2","pure_quanta","I144";
;
PART_NUMBER"CS00002JB13"
TOLERANCE"5%"
MATERIAL"CHIP"
VALUE"0"
$LOCATION"R3720"
WATTAGE"1/16W"
PACK_TYPE"0402LF"
CDS_LIB"pure_quanta"
CDS_LOCATION"R3720"
$SEC"1"
CDS_SEC"1";
"B"
$PN"2"36;
"A"
$PN"1"21;
%"Q_RES"
"1","(-1325,2650)","0","pure_quanta","I145";
;
PART_NUMBER"CS00002JB13"
TOLERANCE"5%"
MATERIAL"CHIP"
VALUE"0"
$LOCATION"R3710"
PACK_TYPE"0402LF"
WATTAGE"1/16W"
CDS_LIB"pure_quanta"
CDS_LOCATION"R3710"
$SEC"1"
CDS_SEC"1";
"B"
$PN"2"17;
"A"
$PN"1"14;
%"UNIVERSAL_POWER"
"1","(-2425,3275)","0","logical_power","I146";
;
HDL_POWER"P3V3_AUX"
CDS_LIB"logical_power";
"A"1;
%"Q_RES"
"2","(-2425,3000)","2","pure_quanta","I147";
;
PART_NUMBER"CS31002FB08"
TOLERANCE"1%"
MATERIAL"EMPTY"
PACK_TYPE"0402LF"
VALUE"10K"
WATTAGE"1/16W"
$LOCATION"R3705"
CDS_LIB"pure_quanta"
CDS_LOCATION"R3705"
$SEC"1"
CDS_SEC"1";
"A"
$PN"1"1;
"B"
$PN"2"14;
%"UNIVERSAL_GND"
"1","(700,1925)","0","logical_power","I149";
;
CDS_LIB"logical_power"
HDL_POWER"GND";
"A"6;
%"Q_RES"
"2","(-3150,75)","0","pure_quanta","I2";
;
PART_NUMBER"CS21002FB06"
VALUE"1K"
PACK_TYPE"0402LF"
MATERIAL"CHIP"
WATTAGE"1/16W"
TOLERANCE"1%"
$LOCATION"R3704"
CDS_LIB"pure_quanta"
CDS_LOCATION"R3704"
$SEC"1"
CDS_SEC"1";
"A"
$PN"1"53;
"B"
$PN"2"9;
%"Q_RES"
"2","(-3150,725)","0","pure_quanta","I3";
;
PART_NUMBER"CS31002FB08"
MATERIAL"EMPTY"
TOLERANCE"1%"
PACK_TYPE"0402LF"
VALUE"10K"
WATTAGE"1/16W"
$LOCATION"R3703"
CDS_LIB"pure_quanta"
CDS_LOCATION"R3703"
$SEC"1"
CDS_SEC"1";
"A"
$PN"1"4;
"B"
$PN"2"53;
%"Q_RES"
"1","(1975,-225)","0","pure_quanta","I34";
;
PART_NUMBER"CS22202JB07"
MATERIAL"CHIP"
VALUE"2.2K"
TOLERANCE"5%"
$LOCATION"R3732"
CDS_LIB"pure_quanta"
PACK_TYPE"0402LF"
WATTAGE"1/16W"
CDS_LOCATION"R3732"
$SEC"1"
CDS_SEC"1";
"B"
$PN"2"12;
"A"
$PN"1"3;
%"UNIVERSAL_POWER"
"1","(-3150,1100)","0","logical_power","I4";
;
HDL_POWER"P3V3_AUX"
CDS_LIB"logical_power";
"A"4;
%"Q_RES"
"1","(1975,125)","0","pure_quanta","I48";
;
PART_NUMBER"CS22202JB07"
VALUE"2.2K"
PACK_TYPE"0402LF"
MATERIAL"CHIP"
TOLERANCE"5%"
WATTAGE"1/16W"
$LOCATION"R3729"
CDS_LIB"pure_quanta"
CDS_LOCATION"R3729"
$SEC"1"
CDS_SEC"1";
"B"
$PN"2"44;
"A"
$PN"1"3;
%"Q_RES"
"1","(1975,75)","0","pure_quanta","I49";
;
PART_NUMBER"CS22202JB07"
TOLERANCE"5%"
MATERIAL"CHIP"
VALUE"2.2K"
$LOCATION"R3730"
WATTAGE"1/16W"
PACK_TYPE"0402LF"
CDS_LIB"pure_quanta"
CDS_LOCATION"R3730"
$SEC"1"
CDS_SEC"1";
"B"
$PN"2"45;
"A"
$PN"1"3;
%"UNIVERSAL_GND"
"1","(-2875,-150)","0","logical_power","I5";
;
CDS_LIB"logical_power"
ROOM"IO_SLOT"
HDL_POWER"GND";
"A"8;
%"Q_RES"
"1","(1950,375)","0","pure_quanta","I50";
;
PART_NUMBER"CS22202JB07"
TOLERANCE"5%"
MATERIAL"CHIP"
VALUE"2.2K"
$LOCATION"R3728"
WATTAGE"1/16W"
PACK_TYPE"0402LF"
CDS_LIB"pure_quanta"
CDS_LOCATION"R3728"
$SEC"1"
CDS_SEC"1";
"B"
$PN"2"43;
"A"
$PN"1"3;
%"Q_RES"
"1","(1950,425)","0","pure_quanta","I51";
;
PART_NUMBER"CS22202JB07"
TOLERANCE"5%"
VALUE"2.2K"
WATTAGE"1/16W"
MATERIAL"CHIP"
PACK_TYPE"0402LF"
$LOCATION"R3727"
CDS_LIB"pure_quanta"
CDS_LOCATION"R3727"
$SEC"1"
CDS_SEC"1";
"B"
$PN"2"46;
"A"
$PN"1"3;
%"Q_RES"
"1","(1950,650)","0","pure_quanta","I52";
;
PART_NUMBER"CS22202JB07"
MATERIAL"CHIP"
VALUE"2.2K"
TOLERANCE"5%"
$LOCATION"R3726"
CDS_LIB"pure_quanta"
PACK_TYPE"0402LF"
WATTAGE"1/16W"
CDS_LOCATION"R3726"
$SEC"1"
CDS_SEC"1";
"B"
$PN"2"48;
"A"
$PN"1"3;
%"Q_RES"
"1","(1950,700)","0","pure_quanta","I53";
;
PART_NUMBER"CS22202JB07"
MATERIAL"CHIP"
PACK_TYPE"0402LF"
TOLERANCE"5%"
WATTAGE"1/16W"
VALUE"2.2K"
$LOCATION"R3725"
CDS_LIB"pure_quanta"
CDS_LOCATION"R3725"
$SEC"1"
CDS_SEC"1";
"B"
$PN"2"50;
"A"
$PN"1"3;
%"UNIVERSAL_POWER"
"1","(1525,1275)","0","logical_power","I54";
;
HDL_POWER"P3V3_AUX"
CDS_LIB"logical_power";
"A"3;
%"Q_RES"
"1","(1950,1075)","0","pure_quanta","I55";
;
PART_NUMBER"CS22202JB07"
PACK_TYPE"0402LF"
MATERIAL"CHIP"
TOLERANCE"5%"
WATTAGE"1/16W"
VALUE"2.2K"
$LOCATION"R3723"
CDS_LIB"pure_quanta"
CDS_LOCATION"R3723"
$SEC"1"
CDS_SEC"1";
"B"
$PN"2"47;
"A"
$PN"1"3;
%"Q_RES"
"1","(1950,1025)","0","pure_quanta","I56";
;
PART_NUMBER"CS22202JB07"
TOLERANCE"5%"
MATERIAL"CHIP"
VALUE"2.2K"
$LOCATION"R3724"
CDS_LIB"pure_quanta"
PACK_TYPE"0402LF"
WATTAGE"1/16W"
CDS_LOCATION"R3724"
$SEC"1"
CDS_SEC"1";
"B"
$PN"2"49;
"A"
$PN"1"3;
%"Q_RES"
"2","(-2875,75)","0","pure_quanta","I6";
;
PART_NUMBER"CS21002FB06"
PACK_TYPE"0402LF"
VALUE"1K"
MATERIAL"CHIP"
WATTAGE"1/16W"
TOLERANCE"1%"
$LOCATION"R3707"
CDS_LIB"pure_quanta"
CDS_LOCATION"R3707"
$SEC"1"
CDS_SEC"1";
"A"
$PN"1"52;
"B"
$PN"2"8;
%"UNIVERSAL_GND"
"1","(-2600,-150)","0","logical_power","I7";
;
CDS_LIB"logical_power"
ROOM"IO_SLOT"
HDL_POWER"GND";
"A"7;
%"Q_RES"
"2","(-2600,75)","0","pure_quanta","I8";
;
PART_NUMBER"CS21002FB06"
PACK_TYPE"0402LF"
WATTAGE"1/16W"
MATERIAL"CHIP"
VALUE"1K"
TOLERANCE"1%"
$LOCATION"R3709"
CDS_LIB"pure_quanta"
CDS_LOCATION"R3709"
$SEC"1"
CDS_SEC"1";
"A"
$PN"1"51;
"B"
$PN"2"7;
%"Q_RES"
"2","(-2875,725)","0","pure_quanta","I9";
;
PART_NUMBER"CS31002FB08"
PACK_TYPE"0402LF"
MATERIAL"EMPTY"
TOLERANCE"1%"
WATTAGE"1/16W"
VALUE"10K"
$LOCATION"R3706"
CDS_LIB"pure_quanta"
CDS_LOCATION"R3706"
$SEC"1"
CDS_SEC"1";
"A"
$PN"1"4;
"B"
$PN"2"52;
%"Q_RES"
"1","(1975,-175)","0","pure_quanta","I98";
;
PART_NUMBER"CS22202JB07"
VALUE"2.2K"
PACK_TYPE"0402LF"
TOLERANCE"5%"
MATERIAL"CHIP"
WATTAGE"1/16W"
$LOCATION"R3731"
CDS_LIB"pure_quanta"
CDS_LOCATION"R3731"
$SEC"1"
CDS_SEC"1";
"B"
$PN"2"13;
"A"
$PN"1"3;
%"Q_RES"
"1","(1975,-475)","0","pure_quanta","I99";
;
PART_NUMBER"CS22202JB07"
MATERIAL"EMPTY"
VALUE"2.2K"
TOLERANCE"5%"
$LOCATION"R4270"
WATTAGE"1/16W"
PACK_TYPE"0402LF"
CDS_LIB"pure_quanta"
CDS_LOCATION"R4270"
$SEC"1"
CDS_SEC"1";
"B"
$PN"2"10;
"A"
$PN"1"3;
END.
